# BASEBOARD_FAB2 (Tioga Pass) — schematic netlist excerpt (pin names and nets, part order shuffled) for the footprints in the layout excerpt that follows; sources: Cadence DE-HDL packaged netlist, KiCad conversion of Wiwynn_Tioga_Pass_MB.brd

J6L2  SCONN288_H44441003  SCONN  pkg PIP  page 52
  \12v\(1)  = P12V_NVDIMM_DEF
  VSS(93)  = GND
  DQ(4)  = M_E_DQ<4>
  VSS(92)  = GND
  DQ(0)  = M_E_DQ<0>
  VSS(91)  = GND
  DQS9P  = M_E_DQS_DP<9>
  DQS9N  = M_E_DQS_DN<9>
  VSS(90)  = GND
  DQ(6)  = M_E_DQ<6>
  VSS(89)  = GND
  DQ(2)  = M_E_DQ<2>
  VSS(88)  = GND
  DQ(12)  = M_E_DQ<12>
  VSS(87)  = GND
  DQ(8)  = M_E_DQ<8>
  VSS(86)  = GND
  DQS10P  = M_E_DQS_DP<10>
  DQS10N  = M_E_DQS_DN<10>
  VSS(85)  = GND
  DQ(14)  = M_E_DQ<14>
  VSS(84)  = GND
  DQ(10)  = M_E_DQ<10>
  VSS(83)  = GND
  DQ(20)  = M_E_DQ<20>
  VSS(82)  = GND
  DQ(16)  = M_E_DQ<16>
  VSS(81)  = GND
  DQS11P  = M_E_DQS_DP<11>
  DQS11N  = M_E_DQS_DN<11>
  VSS(80)  = GND
  DQ(22)  = M_E_DQ<22>
  VSS(79)  = GND
  DQ(18)  = M_E_DQ<18>
  VSS(78)  = GND
  DQ(28)  = M_E_DQ<28>
  VSS(77)  = GND
  DQ(24)  = M_E_DQ<24>
  VSS(76)  = GND
  DQS12P  = M_E_DQS_DP<12>
  DQS12N  = M_E_DQS_DN<12>
  VSS(75)  = GND
  DQ(30)  = M_E_DQ<30>
  VSS(74)  = GND
  DQ(26)  = M_E_DQ<26>
  VSS(73)  = GND
  CB(4)  = M_E_ECC<4>
  VSS(72)  = GND
  CB(0)  = M_E_ECC<0>
  VSS(71)  = GND
  DQS17P  = M_E_DQS_DP<17>
  DQS17N  = M_E_DQS_DN<17>
  VSS(70)  = GND
  CB(6)  = M_E_ECC<6>
  VSS(69)  = GND
  CB(2)  = M_E_ECC<2>
  VSS(68)  = GND
  RESET_N  = M_DEF_RST_N
  VDD(25)  = PVDDQ_DEF
  CKE(0)  = M_E_CKE<2>
  VDD(24)  = PVDDQ_DEF
  ACT_N  = M_E_ACT_N
  BG(0)  = M_E_BG<0>
  VDD(23)  = PVDDQ_DEF
  A12  = M_E_MA<12>
  A9  = M_E_MA<9>
  VDD(22)  = PVDDQ_DEF
  A8  = M_E_MA<8>
  A6  = M_E_MA<6>
  VDD(21)  = PVDDQ_DEF
  A3  = M_E_MA<3>
  A1  = M_E_MA<1>
  VDD(20)  = PVDDQ_DEF
  CK0P  = M_E_CLK_DP<2>
  CK0N  = M_E_CLK_DN<2>
  VDD(19)  = PVDDQ_DEF
  VTT(1)  = PVTT_DEF
  EVENT_N  = FM_DIMM_EVENT_COD_N
  A0  = M_E_MA<0>
  VDD(18)  = PVDDQ_DEF
  BA(0)  = M_E_BA<0>
  A16_RAS_N  = M_E_MA<16>
  VDD(17)  = PVDDQ_DEF
  S0_N  = M_E_CS_N<4>
  VDD(16)  = PVDDQ_DEF
  A15_CAS_N  = M_E_MA<15>
  ODT(0)  = M_E_ODT<2>
  VDD(15)  = PVDDQ_DEF
  S1_N  = M_E_CS_N<5>
  VDD(14)  = PVDDQ_DEF
  ODT(1)  = M_E_ODT<3>
  VDD(13)  = PVDDQ_DEF
  S2_N_C(0)  = M_E_CS_N<6>
  VSS(67)  = GND
  DQ(36)  = M_E_DQ<36>
  VSS(66)  = GND
  DQ(32)  = M_E_DQ<32>
  VSS(65)  = GND
  DQS13P  = M_E_DQS_DP<13>
  DQS13N  = M_E_DQS_DN<13>
  VSS(64)  = GND
  DQ(38)  = M_E_DQ<38>
  VSS(63)  = GND
  DQ(34)  = M_E_DQ<34>
  VSS(62)  = GND
  DQ(44)  = M_E_DQ<44>
  VSS(61)  = GND
  DQ(40)  = M_E_DQ<40>
  VSS(60)  = GND
  DQS14P  = M_E_DQS_DP<14>
  DQS14N  = M_E_DQS_DN<14>
  VSS(59)  = GND
  DQ(46)  = M_E_DQ<46>
  VSS(58)  = GND
  DQ(42)  = M_E_DQ<42>
  VSS(57)  = GND
  DQ(52)  = M_E_DQ<52>
  VSS(56)  = GND
  DQ(48)  = M_E_DQ<48>
  VSS(55)  = GND
  DQS15P  = M_E_DQS_DP<15>
  DQS15N  = M_E_DQS_DN<15>
  VSS(54)  = GND
  DQ(54)  = M_E_DQ<54>
  VSS(53)  = GND
  DQ(50)  = M_E_DQ<50>
  VSS(52)  = GND
  DQ(60)  = M_E_DQ<60>
  VSS(51)  = GND
  DQ(56)  = M_E_DQ<56>
  VSS(50)  = GND
  DQS16P  = M_E_DQS_DP<16>
  DQS16N  = M_E_DQS_DN<16>
  VSS(49)  = GND
  DQ(62)  = M_E_DQ<62>
  VSS(48)  = GND
  DQ(58)  = M_E_DQ<58>
  VSS(47)  = GND
  SA(0)  = PVPP_DEF
  SA(1)  = PVPP_DEF
  SCL  = SMB_DDR_DEF_VPP_SCL
  VPP(4)  = PVPP_DEF
  VPP(3)  = PVPP_DEF
  RFU(2)  = TP_CH_E_DIMM_E1_RFU_2
  \12v\(0)  = P12V_NVDIMM_DEF
  VREFCA  = M_E_VREF
  VSS(46)  = GND
  DQ(5)  = M_E_DQ<5>
  VSS(45)  = GND
  DQ(1)  = M_E_DQ<1>
  VSS(44)  = GND
  DQS0N  = M_E_DQS_DN<0>
  DQS0P  = M_E_DQS_DP<0>
  VSS(43)  = GND
  DQ(7)  = M_E_DQ<7>
  VSS(42)  = GND
  DQ(3)  = M_E_DQ<3>
  VSS(41)  = GND
  DQ(13)  = M_E_DQ<13>
  VSS(40)  = GND
  DQ(9)  = M_E_DQ<9>
  VSS(39)  = GND
  DQS1N  = M_E_DQS_DN<1>
  DQS1P  = M_E_DQS_DP<1>
  VSS(38)  = GND
  DQ(15)  = M_E_DQ<15>
  VSS(37)  = GND
  DQ(11)  = M_E_DQ<11>
  VSS(36)  = GND
  DQ(21)  = M_E_DQ<21>
  VSS(35)  = GND
  DQ(17)  = M_E_DQ<17>
  VSS(34)  = GND
  DQS2N  = M_E_DQS_DN<2>
  DQS2P  = M_E_DQS_DP<2>
  VSS(33)  = GND
  DQ(23)  = M_E_DQ<23>
  VSS(32)  = GND
  DQ(19)  = M_E_DQ<19>
  VSS(31)  = GND
  DQ(29)  = M_E_DQ<29>
  VSS(30)  = GND
  DQ(25)  = M_E_DQ<25>
  VSS(29)  = GND
  DQS3N  = M_E_DQS_DN<3>
  DQS3P  = M_E_DQS_DP<3>
  VSS(28)  = GND
  DQ(31)  = M_E_DQ<31>
  VSS(27)  = GND
  DQ(27)  = M_E_DQ<27>
  VSS(26)  = GND
  CB(5)  = M_E_ECC<5>
  VSS(25)  = GND
  CB(1)  = M_E_ECC<1>
  VSS(24)  = GND
  DQS8N  = M_E_DQS_DN<8>
  DQS8P  = M_E_DQS_DP<8>
  VSS(23)  = GND
  CB(7)  = M_E_ECC<7>
  VSS(22)  = GND
  CB(3)  = M_E_ECC<3>
  VSS(21)  = GND
  CKE(1)  = M_E_CKE<3>
  VDD(12)  = PVDDQ_DEF
  RFU(0)  = TP_CH_E_DIMM_E1_RFU_0
  VDD(11)  = PVDDQ_DEF
  BG(1)  = M_E_BG<1>
  ALERT_N  = M_E_ALERT_N
  VDD(10)  = PVDDQ_DEF
  A11  = M_E_MA<11>
  A7  = M_E_MA<7>
  VDD(9)  = PVDDQ_DEF
  A5  = M_E_MA<5>
  A4  = M_E_MA<4>
  VDD(8)  = PVDDQ_DEF
  A2  = M_E_MA<2>
  VDD(7)  = PVDDQ_DEF
  CK1P  = M_E_CLK_DP<3>
  CK1N  = M_E_CLK_DN<3>
  VDD(6)  = PVDDQ_DEF
  VTT(0)  = PVTT_DEF
  PAR  = M_E_PAR
  VDD(5)  = PVDDQ_DEF
  BA(1)  = M_E_BA<1>
  A10  = M_E_MA<10>
  VDD(4)  = PVDDQ_DEF
  RFU(1)  = TP_CH_E_DIMM_E1_RFU_1
  A14_WE_N  = M_E_MA<14>
  VDD(3)  = PVDDQ_DEF
  SAVE_N_NC  = FM_ADR_COMPLETE_DEF_N
  VDD(2)  = PVDDQ_DEF
  A13  = M_E_MA<13>
  VDD(1)  = PVDDQ_DEF
  A17  = M_E_MA<17>
  C(2)  = M_E_C<2>
  VDD(0)  = PVDDQ_DEF
  S3_N_C(1)  = M_E_CS_N<7>
  SA(2)  = GND
  VSS(20)  = GND
  DQ(37)  = M_E_DQ<37>
  VSS(19)  = GND
  DQ(33)  = M_E_DQ<33>
  VSS(18)  = GND
  DQS4N  = M_E_DQS_DN<4>
  DQS4P  = M_E_DQS_DP<4>
  VSS(17)  = GND
  DQ(39)  = M_E_DQ<39>
  VSS(16)  = GND
  DQ(35)  = M_E_DQ<35>
  VSS(15)  = GND
  DQ(45)  = M_E_DQ<45>
  VSS(14)  = GND
  DQ(41)  = M_E_DQ<41>
  VSS(13)  = GND
  DQS5N  = M_E_DQS_DN<5>
  DQS5P  = M_E_DQS_DP<5>
  VSS(12)  = GND
  DQ(47)  = M_E_DQ<47>
  VSS(11)  = GND
  DQ(43)  = M_E_DQ<43>
  VSS(10)  = GND
  DQ(53)  = M_E_DQ<53>
  VSS(9)  = GND
  DQ(49)  = M_E_DQ<49>
  VSS(8)  = GND
  DQS6N  = M_E_DQS_DN<6>
  DQS6P  = M_E_DQS_DP<6>
  VSS(7)  = GND
  DQ(55)  = M_E_DQ<55>
  VSS(6)  = GND
  DQ(51)  = M_E_DQ<51>
  VSS(5)  = GND
  DQ(61)  = M_E_DQ<61>
  VSS(4)  = GND
  DQ(57)  = M_E_DQ<57>
  VSS(3)  = GND
  DQS7N  = M_E_DQS_DN<7>
  DQS7P  = M_E_DQS_DP<7>
  VSS(2)  = GND
  DQ(63)  = M_E_DQ<63>
  VSS(1)  = GND
  DQ(59)  = M_E_DQ<59>
  VSS(0)  = GND
  VDDSPD  = PVPP_DEF
  SDA  = SMB_DDR_DEF_VPP_SDA
  VPP(1)  = PVPP_DEF
  VPP(0)  = PVPP_DEF
  VPP(2)  = PVPP_DEF

(kicad_pcb
	(version 20260206)
	(generator "pcbnew")
	(generator_version "10.0")
	(general
		(thickness 1.6)
		(legacy_teardrops no)
	)
	(paper "A4")
	(title_block
		(title "Wiwynn_Tioga_Pass_MB.brd")
		(comment 1 "Tioga Pass / footprint 3319 of 4770 (J6L2), pads 152-201 of 291")
	)
	(layers
		(0 "F.Cu" signal "TOP")
		(4 "In1.Cu" signal "L2GND")
		(6 "In2.Cu" signal "L3")
		(8 "In3.Cu" signal "L4GND")
		(10 "In4.Cu" signal "L5")
		(12 "In5.Cu" signal "L6GND")
		(14 "In6.Cu" signal "L7VCC")
		(16 "In7.Cu" signal "L8VCC")
		(18 "In8.Cu" signal "L9GND")
		(20 "In9.Cu" signal "L10")
		(22 "In10.Cu" signal "L11GND")
		(24 "In11.Cu" signal "L12")
		(26 "In12.Cu" signal "L13GND")
		(2 "B.Cu" signal "BOTTOM")
		(9 "F.Adhes" user "F.Adhesive")
		(11 "B.Adhes" user "B.Adhesive")
		(13 "F.Paste" user "Package Geometry/Pastemask Top")
		(15 "B.Paste" user "Package Geometry/Pastemask Bottom")
		(5 "F.SilkS" user "Ref Des/Silkscreen Top")
		(7 "B.SilkS" user "Ref Des/Silkscreen Bottom")
		(1 "F.Mask" user "Board Geometry/Soldermask Top")
		(3 "B.Mask" user "Board Geometry/Soldermask Bottom")
		(17 "Dwgs.User" user "User.Drawings")
		(19 "Cmts.User" user "User.Comments")
		(21 "Eco1.User" user "User.Eco1")
		(23 "Eco2.User" user "User.Eco2")
		(25 "Edge.Cuts" user "Board Geometry/Outline")
		(27 "Margin" user)
		(31 "F.CrtYd" user "Package Geometry/Place Bound Top")
		(29 "B.CrtYd" user "Package Geometry/Place Bound Bottom")
		(35 "F.Fab" user "Ref Des/Assembly Top")
		(33 "B.Fab" user "Ref Des/Assembly Bottom")
	)
	(footprint ""
		(layer "B.Cu")
		(at 194.700398 -142.477236 90)
		(property "Reference" "J6L2"
			(at 2.276348 38.21811 0)
			(unlocked yes)
			(layer "B.SilkS")
			(effects
				(font
					(size 0.7874 0.5842)
					(thickness 0.1524)
				)
				(justify left mirror)
			)
		)
		(property "Value" ""
			(at 0 0 90)
			(layer "B.Fab")
			(effects
				(font
					(size 1.27 1.27)
				)
				(justify mirror)
			)
		)
		(duplicate_pad_numbers_are_jumpers no)
		(pad "149" smd rect
			(at -4.59994 3.400044 270)
			(size 1.8034 0.508)
			(layers "B.Cu" "B.Mask" "B.Paste")
			(net "GND")
		)
		(pad "150" smd rect
			(at -4.59994 4.249928 270)
			(size 1.8034 0.508)
			(layers "B.Cu" "B.Mask" "B.Paste")
			(net "M_E_DQ<1>")
		)
		(pad "151" smd rect
			(at -4.59994 5.100066 270)
			(size 1.8034 0.508)
			(layers "B.Cu" "B.Mask" "B.Paste")
			(net "GND")
		)
		(pad "152" smd rect
			(at -4.59994 5.94995 270)
			(size 1.8034 0.508)
			(layers "B.Cu" "B.Mask" "B.Paste")
			(net "M_E_DQS_DN<0>")
		)
		(pad "153" smd rect
			(at -4.59994 6.800088 270)
			(size 1.8034 0.508)
			(layers "B.Cu" "B.Mask" "B.Paste")
			(net "M_E_DQS_DP<0>")
		)
		(pad "154" smd rect
			(at -4.59994 7.649972 270)
			(size 1.8034 0.508)
			(layers "B.Cu" "B.Mask" "B.Paste")
			(net "GND")
		)
		(pad "155" smd rect
			(at -4.59994 8.50011 270)
			(size 1.8034 0.508)
			(layers "B.Cu" "B.Mask" "B.Paste")
			(net "M_E_DQ<7>")
		)
		(pad "156" smd rect
			(at -4.59994 9.349994 270)
			(size 1.8034 0.508)
			(layers "B.Cu" "B.Mask" "B.Paste")
			(net "GND")
		)
		(pad "157" smd rect
			(at -4.59994 10.199878 270)
			(size 1.8034 0.508)
			(layers "B.Cu" "B.Mask" "B.Paste")
			(net "M_E_DQ<3>")
		)
		(pad "158" smd rect
			(at -4.59994 11.050016 270)
			(size 1.8034 0.508)
			(layers "B.Cu" "B.Mask" "B.Paste")
			(net "GND")
		)
		(pad "159" smd rect
			(at -4.59994 11.8999 270)
			(size 1.8034 0.508)
			(layers "B.Cu" "B.Mask" "B.Paste")
			(net "M_E_DQ<13>")
		)
		(pad "160" smd rect
			(at -4.59994 12.750038 270)
			(size 1.8034 0.508)
			(layers "B.Cu" "B.Mask" "B.Paste")
			(net "GND")
		)
		(pad "161" smd rect
			(at -4.59994 13.599922 270)
			(size 1.8034 0.508)
			(layers "B.Cu" "B.Mask" "B.Paste")
			(net "M_E_DQ<9>")
		)
		(pad "162" smd rect
			(at -4.59994 14.45006 270)
			(size 1.8034 0.508)
			(layers "B.Cu" "B.Mask" "B.Paste")
			(net "GND")
		)
		(pad "163" smd rect
			(at -4.59994 15.299944 270)
			(size 1.8034 0.508)
			(layers "B.Cu" "B.Mask" "B.Paste")
			(net "M_E_DQS_DN<1>")
		)
		(pad "164" smd rect
			(at -4.59994 16.150082 270)
			(size 1.8034 0.508)
			(layers "B.Cu" "B.Mask" "B.Paste")
			(net "M_E_DQS_DP<1>")
		)
		(pad "165" smd rect
			(at -4.59994 16.999966 270)
			(size 1.8034 0.508)
			(layers "B.Cu" "B.Mask" "B.Paste")
			(net "GND")
		)
		(pad "166" smd rect
			(at -4.59994 17.850104 270)
			(size 1.8034 0.508)
			(layers "B.Cu" "B.Mask" "B.Paste")
			(net "M_E_DQ<15>")
		)
		(pad "167" smd rect
			(at -4.59994 18.699988 270)
			(size 1.8034 0.508)
			(layers "B.Cu" "B.Mask" "B.Paste")
			(net "GND")
		)
		(pad "168" smd rect
			(at -4.59994 19.550126 270)
			(size 1.8034 0.508)
			(layers "B.Cu" "B.Mask" "B.Paste")
			(net "M_E_DQ<11>")
		)
		(pad "169" smd rect
			(at -4.59994 20.40001 270)
			(size 1.8034 0.508)
			(layers "B.Cu" "B.Mask" "B.Paste")
			(net "GND")
		)
		(pad "170" smd rect
			(at -4.59994 21.249894 270)
			(size 1.8034 0.508)
			(layers "B.Cu" "B.Mask" "B.Paste")
			(net "M_E_DQ<21>")
		)
		(pad "171" smd rect
			(at -4.59994 22.100032 270)
			(size 1.8034 0.508)
			(layers "B.Cu" "B.Mask" "B.Paste")
			(net "GND")
		)
		(pad "172" smd rect
			(at -4.59994 22.949916 270)
			(size 1.8034 0.508)
			(layers "B.Cu" "B.Mask" "B.Paste")
			(net "M_E_DQ<17>")
		)
		(pad "173" smd rect
			(at -4.59994 23.800054 270)
			(size 1.8034 0.508)
			(layers "B.Cu" "B.Mask" "B.Paste")
			(net "GND")
		)
		(pad "174" smd rect
			(at -4.59994 24.649938 270)
			(size 1.8034 0.508)
			(layers "B.Cu" "B.Mask" "B.Paste")
			(net "M_E_DQS_DN<2>")
		)
		(pad "175" smd rect
			(at -4.59994 25.500076 270)
			(size 1.8034 0.508)
			(layers "B.Cu" "B.Mask" "B.Paste")
			(net "M_E_DQS_DP<2>")
		)
		(pad "176" smd rect
			(at -4.59994 26.34996 270)
			(size 1.8034 0.508)
			(layers "B.Cu" "B.Mask" "B.Paste")
			(net "GND")
		)
		(pad "177" smd rect
			(at -4.59994 27.200098 270)
			(size 1.8034 0.508)
			(layers "B.Cu" "B.Mask" "B.Paste")
			(net "M_E_DQ<23>")
		)
		(pad "178" smd rect
			(at -4.59994 28.049982 270)
			(size 1.8034 0.508)
			(layers "B.Cu" "B.Mask" "B.Paste")
			(net "GND")
		)
		(pad "179" smd rect
			(at -4.59994 28.90012 270)
			(size 1.8034 0.508)
			(layers "B.Cu" "B.Mask" "B.Paste")
			(net "M_E_DQ<19>")
		)
		(pad "180" smd rect
			(at -4.59994 29.750004 270)
			(size 1.8034 0.508)
			(layers "B.Cu" "B.Mask" "B.Paste")
			(net "GND")
		)
		(pad "181" smd rect
			(at -4.59994 30.599888 270)
			(size 1.8034 0.508)
			(layers "B.Cu" "B.Mask" "B.Paste")
			(net "M_E_DQ<29>")
		)
		(pad "182" smd rect
			(at -4.59994 31.450026 270)
			(size 1.8034 0.508)
			(layers "B.Cu" "B.Mask" "B.Paste")
			(net "GND")
		)
		(pad "183" smd rect
			(at -4.59994 32.29991 270)
			(size 1.8034 0.508)
			(layers "B.Cu" "B.Mask" "B.Paste")
			(net "M_E_DQ<25>")
		)
		(pad "184" smd rect
			(at -4.59994 33.150048 270)
			(size 1.8034 0.508)
			(layers "B.Cu" "B.Mask" "B.Paste")
			(net "GND")
		)
		(pad "185" smd rect
			(at -4.59994 33.999932 270)
			(size 1.8034 0.508)
			(layers "B.Cu" "B.Mask" "B.Paste")
			(net "M_E_DQS_DN<3>")
		)
		(pad "186" smd rect
			(at -4.59994 34.85007 270)
			(size 1.8034 0.508)
			(layers "B.Cu" "B.Mask" "B.Paste")
			(net "M_E_DQS_DP<3>")
		)
		(pad "187" smd rect
			(at -4.59994 35.699954 270)
			(size 1.8034 0.508)
			(layers "B.Cu" "B.Mask" "B.Paste")
			(net "GND")
		)
		(pad "188" smd rect
			(at -4.59994 36.550092 270)
			(size 1.8034 0.508)
			(layers "B.Cu" "B.Mask" "B.Paste")
			(net "M_E_DQ<31>")
		)
		(pad "189" smd rect
			(at -4.59994 37.399976 270)
			(size 1.8034 0.508)
			(layers "B.Cu" "B.Mask" "B.Paste")
			(net "GND")
		)
		(pad "190" smd rect
			(at -4.59994 38.250114 270)
			(size 1.8034 0.508)
			(layers "B.Cu" "B.Mask" "B.Paste")
			(net "M_E_DQ<27>")
		)
		(pad "191" smd rect
			(at -4.59994 39.099998 270)
			(size 1.8034 0.508)
			(layers "B.Cu" "B.Mask" "B.Paste")
			(net "GND")
		)
		(pad "192" smd rect
			(at -4.59994 39.949882 270)
			(size 1.8034 0.508)
			(layers "B.Cu" "B.Mask" "B.Paste")
			(net "M_E_ECC<5>")
		)
		(pad "193" smd rect
			(at -4.59994 40.80002 270)
			(size 1.8034 0.508)
			(layers "B.Cu" "B.Mask" "B.Paste")
			(net "GND")
		)
		(pad "194" smd rect
			(at -4.59994 41.649904 270)
			(size 1.8034 0.508)
			(layers "B.Cu" "B.Mask" "B.Paste")
			(net "M_E_ECC<1>")
		)
		(pad "195" smd rect
			(at -4.59994 42.500042 270)
			(size 1.8034 0.508)
			(layers "B.Cu" "B.Mask" "B.Paste")
			(net "GND")
		)
		(pad "196" smd rect
			(at -4.59994 43.349926 270)
			(size 1.8034 0.508)
			(layers "B.Cu" "B.Mask" "B.Paste")
			(net "M_E_DQS_DN<8>")
		)
		(pad "197" smd rect
			(at -4.59994 44.200064 270)
			(size 1.8034 0.508)
			(layers "B.Cu" "B.Mask" "B.Paste")
			(net "M_E_DQS_DP<8>")
		)
		(pad "198" smd rect
			(at -4.59994 45.049948 270)
			(size 1.8034 0.508)
			(layers "B.Cu" "B.Mask" "B.Paste")
			(net "GND")
		)
	)
)
